(kicad_pcb
	(version 20260206)
	(generator "pcbnew")
	(generator_version "10.0")
	(general
		(thickness 1.6)
		(legacy_teardrops no)
	)
	(paper "A4")
	(title_block
		(title "fcb — Lightning_FCB_BRD.brd")
		(comment 1 "Lightning (Wiwynn / Facebook NVMe JBOF) / footprints 239-244 of 495")
	)
	(layers
		(0 "F.Cu" signal "TOP")
		(4 "In1.Cu" signal "L2GND")
		(6 "In2.Cu" signal "L3VCC")
		(2 "B.Cu" signal "BOTTOM")
		(9 "F.Adhes" user "F.Adhesive")
		(11 "B.Adhes" user "B.Adhesive")
		(13 "F.Paste" user "Package Geometry/Pastemask Top")
		(15 "B.Paste" user "Package Geometry/Pastemask Bottom")
		(5 "F.SilkS" user "Ref Des/Silkscreen Top")
		(7 "B.SilkS" user "Ref Des/Silkscreen Bottom")
		(1 "F.Mask" user "Board Geometry/Soldermask Top")
		(3 "B.Mask" user "Board Geometry/Soldermask Bottom")
		(17 "Dwgs.User" user "User.Drawings")
		(19 "Cmts.User" user "User.Comments")
		(21 "Eco1.User" user "User.Eco1")
		(23 "Eco2.User" user "User.Eco2")
		(25 "Edge.Cuts" user "Board Geometry/Outline")
		(27 "Margin" user)
		(31 "F.CrtYd" user "Package Geometry/Place Bound Top")
		(29 "B.CrtYd" user "Package Geometry/Place Bound Bottom")
		(35 "F.Fab" user "Ref Des/Assembly Top")
		(33 "B.Fab" user "Ref Des/Assembly Bottom")
	)
	(footprint ""
		(layer "F.Cu")
		(at 23.63851 -151.325834)
		(property "Reference" "R12"
			(at 0 0 0)
			(layer "F.SilkS")
			(hide yes)
			(effects
				(font
					(size 1.27 1.27)
				)
			)
		)
		(property "Value" "4K7R2F-GP"
			(at 0.064008 -3.993896 0)
			(unlocked yes)
			(layer "F.Fab")
			(hide yes)
			(effects
				(font
					(size 1.016 1.016)
					(thickness 0.1524)
				)
			)
		)
		(property "Device Type" "R402H16"
			(at 0.064008 -5.517896 0)
			(unlocked yes)
			(layer "F.Fab")
			(hide yes)
			(effects
				(font
					(size 1.016 1.016)
					(thickness 0.1524)
				)
			)
		)
		(duplicate_pad_numbers_are_jumpers no)
		(fp_line
			(start -0.508 -0.9398)
			(end -0.508 0.9398)
			(stroke
				(width 0.1524)
				(type default)
			)
			(layer "F.SilkS")
		)
		(fp_line
			(start 0.508 -0.9398)
			(end -0.508 -0.9398)
			(stroke
				(width 0.1524)
				(type default)
			)
			(layer "F.SilkS")
		)
		(fp_rect
			(start -0.508 0.9398)
			(end 0.508 -0.9398)
			(stroke
				(width 0)
				(type default)
			)
			(fill no)
			(layer "F.CrtYd")
		)
		(fp_rect
			(start -0.508 0.9398)
			(end 0.508 -0.9398)
			(stroke
				(width 0)
				(type default)
			)
			(fill no)
			(layer "F.Fab")
		)
		(pad "1" smd custom
			(at 0 -0.4445)
			(size 0.1397 0.1397)
			(layers "F.Cu" "F.Mask" "F.Paste")
			(net "NCT7904_RESET")
			(options
				(clearance outline)
				(anchor circle)
			)
			(primitives
				(gr_poly
					(pts
						(arc
							(start -0.1778 -0.2794)
							(mid -0.249642 -0.249642)
							(end -0.2794 -0.1778)
						)
						(arc
							(start -0.2794 0.1778)
							(mid -0.249642 0.249642)
							(end -0.1778 0.2794)
						)
						(arc
							(start 0.1778 0.2794)
							(mid 0.249642 0.249642)
							(end 0.2794 0.1778)
						)
						(arc
							(start 0.2794 -0.1778)
							(mid 0.249642 -0.249642)
							(end 0.1778 -0.2794)
						)
					)
					(width 0)
					(fill yes)
				)
			)
		)
		(pad "2" smd custom
			(at 0 0.4445)
			(size 0.1397 0.1397)
			(layers "F.Cu" "F.Mask" "F.Paste")
			(net "P3V3")
			(options
				(clearance outline)
				(anchor circle)
			)
			(primitives
				(gr_poly
					(pts
						(arc
							(start -0.1778 -0.2794)
							(mid -0.249642 -0.249642)
							(end -0.2794 -0.1778)
						)
						(arc
							(start -0.2794 0.1778)
							(mid -0.249642 0.249642)
							(end -0.1778 0.2794)
						)
						(arc
							(start 0.1778 0.2794)
							(mid 0.249642 0.249642)
							(end 0.2794 0.1778)
						)
						(arc
							(start 0.2794 -0.1778)
							(mid 0.249642 -0.249642)
							(end 0.1778 -0.2794)
						)
					)
					(width 0)
					(fill yes)
				)
			)
		)
	)
	(footprint ""
		(layer "F.Cu")
		(at 16.053308 -287.311338)
		(property "Reference" "R98"
			(at 0 0 0)
			(layer "F.SilkS")
			(hide yes)
			(effects
				(font
					(size 1.27 1.27)
				)
			)
		)
		(property "Value" "27KR3F-GP"
			(at -0.0254 -2.5146 0)
			(unlocked yes)
			(layer "F.Fab")
			(hide yes)
			(effects
				(font
					(size 1.016 1.016)
					(thickness 0.1524)
				)
			)
		)
		(property "Device Type" "R603H22"
			(at -0.0254 -4.0386 0)
			(unlocked yes)
			(layer "F.Fab")
			(hide yes)
			(effects
				(font
					(size 1.016 1.016)
					(thickness 0.1524)
				)
			)
		)
		(duplicate_pad_numbers_are_jumpers no)
		(fp_line
			(start -0.4826 0)
			(end -0.2032 0)
			(stroke
				(width 0.2032)
				(type default)
			)
			(layer "F.SilkS")
		)
		(fp_line
			(start 0.2032 0)
			(end 0.4826 0)
			(stroke
				(width 0.2032)
				(type default)
			)
			(layer "F.SilkS")
		)
		(fp_rect
			(start -0.5842 1.3335)
			(end 0.5842 -1.3335)
			(stroke
				(width 0)
				(type default)
			)
			(fill no)
			(layer "F.CrtYd")
		)
		(fp_rect
			(start -0.5842 1.3335)
			(end 0.5842 -1.3335)
			(stroke
				(width 0)
				(type default)
			)
			(fill no)
			(layer "F.Fab")
		)
		(pad "1" smd custom
			(at 0 -0.762)
			(size 0.2159 0.2159)
			(layers "F.Cu" "F.Mask" "F.Paste")
			(net "FANIN_3")
			(options
				(clearance outline)
				(anchor circle)
			)
			(primitives
				(gr_poly
					(pts
						(arc
							(start -0.3302 -0.4318)
							(mid -0.402042 -0.402042)
							(end -0.4318 -0.3302)
						)
						(arc
							(start -0.4318 0.3302)
							(mid -0.402042 0.402042)
							(end -0.3302 0.4318)
						)
						(arc
							(start 0.3302 0.4318)
							(mid 0.402042 0.402042)
							(end 0.4318 0.3302)
						)
						(arc
							(start 0.4318 -0.3302)
							(mid 0.402042 -0.402042)
							(end 0.3302 -0.4318)
						)
					)
					(width 0)
					(fill yes)
				)
			)
		)
		(pad "2" smd custom
			(at 0 0.762)
			(size 0.2159 0.2159)
			(layers "F.Cu" "F.Mask" "F.Paste")
			(net "FAN_TACH3")
			(options
				(clearance outline)
				(anchor circle)
			)
			(primitives
				(gr_poly
					(pts
						(arc
							(start -0.3302 -0.4318)
							(mid -0.402042 -0.402042)
							(end -0.4318 -0.3302)
						)
						(arc
							(start -0.4318 0.3302)
							(mid -0.402042 0.402042)
							(end -0.3302 0.4318)
						)
						(arc
							(start 0.3302 0.4318)
							(mid 0.402042 0.402042)
							(end 0.4318 0.3302)
						)
						(arc
							(start 0.4318 -0.3302)
							(mid 0.402042 -0.402042)
							(end 0.3302 -0.4318)
						)
					)
					(width 0)
					(fill yes)
				)
			)
		)
	)
	(footprint ""
		(layer "F.Cu")
		(at 26.4922 -251.6632 -90)
		(property "Reference" "C13"
			(at 0 0 270)
			(layer "F.SilkS")
			(hide yes)
			(effects
				(font
					(size 1.27 1.27)
				)
			)
		)
		(property "Value" "SC1U16V3KX-5GP"
			(at 0 -2.8194 270)
			(unlocked yes)
			(layer "F.Fab")
			(hide yes)
			(effects
				(font
					(size 1.016 1.016)
					(thickness 0.1524)
				)
			)
		)
		(property "Device Type" "C603H36"
			(at 0 -4.3434 270)
			(unlocked yes)
			(layer "F.Fab")
			(hide yes)
			(effects
				(font
					(size 1.016 1.016)
					(thickness 0.1524)
				)
			)
		)
		(duplicate_pad_numbers_are_jumpers no)
		(fp_line
			(start 0.508 0)
			(end -0.508 0)
			(stroke
				(width 0.2032)
				(type default)
			)
			(layer "F.SilkS")
		)
		(fp_rect
			(start -0.5842 1.3335)
			(end 0.5842 -1.3335)
			(stroke
				(width 0)
				(type default)
			)
			(fill no)
			(layer "F.CrtYd")
		)
		(fp_rect
			(start -0.5842 1.3335)
			(end 0.5842 -1.3335)
			(stroke
				(width 0)
				(type default)
			)
			(fill no)
			(layer "F.Fab")
		)
		(pad "1" smd custom
			(at 0 -0.762 270)
			(size 0.2159 0.2159)
			(layers "F.Cu" "F.Mask" "F.Paste")
			(net "P3V3")
			(options
				(clearance outline)
				(anchor circle)
			)
			(primitives
				(gr_poly
					(pts
						(arc
							(start -0.3302 -0.4318)
							(mid -0.402042 -0.402042)
							(end -0.4318 -0.3302)
						)
						(arc
							(start -0.4318 0.3302)
							(mid -0.402042 0.402042)
							(end -0.3302 0.4318)
						)
						(arc
							(start 0.3302 0.4318)
							(mid 0.402042 0.402042)
							(end 0.4318 0.3302)
						)
						(arc
							(start 0.4318 -0.3302)
							(mid 0.402042 -0.402042)
							(end 0.3302 -0.4318)
						)
					)
					(width 0)
					(fill yes)
				)
			)
		)
		(pad "2" smd custom
			(at 0 0.762 270)
			(size 0.2159 0.2159)
			(layers "F.Cu" "F.Mask" "F.Paste")
			(net "GND")
			(options
				(clearance outline)
				(anchor circle)
			)
			(primitives
				(gr_poly
					(pts
						(arc
							(start -0.3302 -0.4318)
							(mid -0.402042 -0.402042)
							(end -0.4318 -0.3302)
						)
						(arc
							(start -0.4318 0.3302)
							(mid -0.402042 0.402042)
							(end -0.3302 0.4318)
						)
						(arc
							(start 0.3302 0.4318)
							(mid 0.402042 0.402042)
							(end 0.4318 0.3302)
						)
						(arc
							(start 0.4318 -0.3302)
							(mid 0.402042 -0.402042)
							(end 0.3302 -0.4318)
						)
					)
					(width 0)
					(fill yes)
				)
			)
		)
	)
	(footprint ""
		(layer "F.Cu")
		(at 7.949946 -267.865098 -90)
		(property "Reference" "LED3"
			(at 0 0 270)
			(layer "F.SilkS")
			(hide yes)
			(effects
				(font
					(size 1.27 1.27)
				)
			)
		)
		(property "Value" "LED-RB-6-GP"
			(at -4.6736 3.8354 270)
			(unlocked yes)
			(layer "F.Fab")
			(hide yes)
			(effects
				(font
					(size 1.016 1.016)
					(thickness 0.1524)
				)
			)
		)
		(property "Device Type" "LED-100-3P-067106H325"
			(at -4.6736 2.3114 270)
			(unlocked yes)
			(layer "F.Fab")
			(hide yes)
			(effects
				(font
					(size 1.016 1.016)
					(thickness 0.1524)
				)
			)
		)
		(duplicate_pad_numbers_are_jumpers no)
		(fp_line
			(start -1.7526 10.414)
			(end -1.7526 6.6548)
			(stroke
				(width 0.1524)
				(type default)
			)
			(layer "F.SilkS")
		)
		(fp_line
			(start 1.7526 10.414)
			(end -1.7526 10.414)
			(stroke
				(width 0.1524)
				(type default)
			)
			(layer "F.SilkS")
		)
		(fp_line
			(start -3.6068 6.6548)
			(end -3.6068 -0.889)
			(stroke
				(width 0.1524)
				(type default)
			)
			(layer "F.SilkS")
		)
		(fp_line
			(start -1.7526 6.6548)
			(end -3.6068 6.6548)
			(stroke
				(width 0.1524)
				(type default)
			)
			(layer "F.SilkS")
		)
		(fp_line
			(start 1.7526 6.6548)
			(end 1.7526 10.414)
			(stroke
				(width 0.1524)
				(type default)
			)
			(layer "F.SilkS")
		)
		(fp_line
			(start 3.6068 6.6548)
			(end 1.7526 6.6548)
			(stroke
				(width 0.1524)
				(type default)
			)
			(layer "F.SilkS")
		)
		(fp_line
			(start -3.6068 -0.889)
			(end 3.6068 -0.889)
			(stroke
				(width 0.1524)
				(type default)
			)
			(layer "F.SilkS")
		)
		(fp_line
			(start 3.6068 -0.889)
			(end 3.6068 6.6548)
			(stroke
				(width 0.1524)
				(type default)
			)
			(layer "F.SilkS")
		)
		(fp_circle
			(center -2.54 0)
			(end -2.54 -0.9906)
			(stroke
				(width 0.3048)
				(type default)
			)
			(fill no)
			(layer "F.SilkS")
		)
		(fp_circle
			(center 0 0)
			(end 0 -0.9906)
			(stroke
				(width 0.3048)
				(type default)
			)
			(fill no)
			(layer "F.SilkS")
		)
		(fp_circle
			(center 2.54 0)
			(end 2.54 -0.9906)
			(stroke
				(width 0.3048)
				(type default)
			)
			(fill no)
			(layer "F.SilkS")
		)
		(fp_poly
			(pts
				(xy -1.4986 10.1473) (xy -1.4986 6.4008) (xy -3.3528 6.4008) (xy -3.3528 -0.3937) (xy 3.3528 -0.3937)
				(xy 3.3528 6.4008) (xy 1.4986 6.4008) (xy 1.4986 10.1473)
			)
			(stroke
				(width 0)
				(type default)
			)
			(fill no)
			(layer "F.CrtYd")
		)
		(fp_poly
			(pts
				(xy -2.0066 10.668) (xy 2.0066 10.668) (xy 2.0066 6.9088) (xy 3.8608 6.9088) (xy 3.8608 2.2098)
				(xy 3.3528 2.2098) (xy 3.3528 6.4008) (xy 1.4986 6.4008) (xy 1.4986 10.1473) (xy -1.4986 10.1473)
				(xy -1.4986 6.4008) (xy -3.3528 6.4008) (xy -3.3528 -0.3937) (xy 3.3528 -0.3937) (xy 3.3528 2.1971)
				(xy 3.8608 2.1971) (xy 3.8608 -1.143) (xy -3.8608 -1.143) (xy -3.8608 6.9088) (xy -2.0066 6.9088)
			)
			(stroke
				(width 0)
				(type default)
			)
			(fill no)
			(layer "F.CrtYd")
		)
		(fp_poly
			(pts
				(xy -2.0066 10.668) (xy -2.0066 6.9088) (xy -3.8608 6.9088) (xy -3.8608 -1.143) (xy 3.8608 -1.143)
				(xy 3.8608 6.9088) (xy 2.0066 6.9088) (xy 2.0066 10.668)
			)
			(stroke
				(width 0)
				(type default)
			)
			(fill no)
			(layer "F.Fab")
		)
		(pad "1" thru_hole circle
			(at 2.54 0 270)
			(size 1.27 1.27)
			(drill 0.889)
			(layers "*.Cu" "*.Mask")
			(remove_unused_layers no)
			(net "LED_DR_LED2_BLUE")
			(clearance 0.1651)
			(thermal_gap 0.1651)
		)
		(pad "2" thru_hole circle
			(at 0 0 270)
			(size 1.27 1.27)
			(drill 0.889)
			(layers "*.Cu" "*.Mask")
			(remove_unused_layers no)
			(net "LED_DR_LED2_K")
			(clearance 0.1651)
			(thermal_gap 0.1651)
		)
		(pad "3" thru_hole circle
			(at -2.54 0 270)
			(size 1.27 1.27)
			(drill 0.889)
			(layers "*.Cu" "*.Mask")
			(remove_unused_layers no)
			(net "LED_DR_LED2")
			(clearance 0.1651)
			(thermal_gap 0.1651)
		)
	)
	(footprint ""
		(layer "F.Cu")
		(at 4.040124 -306.660042 -90)
		(property "Reference" "CN3"
			(at 0 0 270)
			(layer "F.SilkS")
			(hide yes)
			(effects
				(font
					(size 1.27 1.27)
				)
			)
		)
		(property "Value" "JWT-CON5-42-GP"
			(at -7.8105 2.9591 270)
			(unlocked yes)
			(layer "F.Fab")
			(hide yes)
			(effects
				(font
					(size 1.016 1.016)
					(thickness 0.1524)
				)
			)
		)
		(property "Device Type" "A2541WR0-1TX5PA-6T-0E"
			(at -7.8105 1.4351 270)
			(unlocked yes)
			(layer "F.Fab")
			(hide yes)
			(effects
				(font
					(size 1.016 1.016)
					(thickness 0.1524)
				)
			)
		)
		(duplicate_pad_numbers_are_jumpers no)
		(fp_line
			(start -6.604 10.287)
			(end 6.604 10.287)
			(stroke
				(width 0.1524)
				(type default)
			)
			(layer "F.SilkS")
		)
		(fp_line
			(start 6.604 10.287)
			(end 6.604 -0.9652)
			(stroke
				(width 0.1524)
				(type default)
			)
			(layer "F.SilkS")
		)
		(fp_line
			(start -6.604 -0.9652)
			(end -6.604 10.287)
			(stroke
				(width 0.1524)
				(type default)
			)
			(layer "F.SilkS")
		)
		(fp_line
			(start 6.604 -0.9652)
			(end -6.604 -0.9652)
			(stroke
				(width 0.1524)
				(type default)
			)
			(layer "F.SilkS")
		)
		(fp_line
			(start -6.731 -1.0922)
			(end -6.731 0.1778)
			(stroke
				(width 0.4064)
				(type default)
			)
			(layer "F.SilkS")
		)
		(fp_line
			(start -5.461 -1.0922)
			(end -6.731 -1.0922)
			(stroke
				(width 0.4064)
				(type default)
			)
			(layer "F.SilkS")
		)
		(fp_circle
			(center -5.08 0)
			(end -5.08 -1.0668)
			(stroke
				(width 0.3048)
				(type default)
			)
			(fill no)
			(layer "F.SilkS")
		)
		(fp_circle
			(center -2.54 0)
			(end -2.54 -1.0668)
			(stroke
				(width 0.3048)
				(type default)
			)
			(fill no)
			(layer "F.SilkS")
		)
		(fp_circle
			(center 0 0)
			(end 0 -1.0668)
			(stroke
				(width 0.3048)
				(type default)
			)
			(fill no)
			(layer "F.SilkS")
		)
		(fp_circle
			(center 2.54 0)
			(end 2.54 -1.0668)
			(stroke
				(width 0.3048)
				(type default)
			)
			(fill no)
			(layer "F.SilkS")
		)
		(fp_circle
			(center 5.08 0)
			(end 5.08 -1.0668)
			(stroke
				(width 0.3048)
				(type default)
			)
			(fill no)
			(layer "F.SilkS")
		)
		(fp_rect
			(start -6.35 10.033)
			(end 6.35 -0.3302)
			(stroke
				(width 0)
				(type default)
			)
			(fill no)
			(layer "F.CrtYd")
		)
		(fp_poly
			(pts
				(xy -6.35 -0.3302) (xy 6.858 -0.3302) (xy 6.858 -1.2192) (xy -6.858 -1.2192) (xy -6.858 10.541)
				(xy 6.858 10.541) (xy 6.858 -0.3175) (xy 6.35 -0.3175) (xy 6.35 10.033) (xy -6.35 10.033)
			)
			(stroke
				(width 0)
				(type default)
			)
			(fill no)
			(layer "F.CrtYd")
		)
		(fp_rect
			(start -6.858 10.541)
			(end 6.858 -1.2192)
			(stroke
				(width 0)
				(type default)
			)
			(fill no)
			(layer "F.Fab")
		)
		(pad "1" thru_hole circle
			(at -5.08 0 270)
			(size 1.4224 1.4224)
			(drill 1.016)
			(layers "*.Cu" "*.Mask")
			(remove_unused_layers no)
			(net "GND")
			(clearance 0.1524)
			(thermal_gap 0.1524)
		)
		(pad "2" thru_hole circle
			(at -2.54 0 270)
			(size 1.4224 1.4224)
			(drill 1.016)
			(layers "*.Cu" "*.Mask")
			(remove_unused_layers no)
			(net "P12V_FAN3")
			(clearance 0.1524)
			(thermal_gap 0.1524)
		)
		(pad "3" thru_hole circle
			(at 0 0 270)
			(size 1.4224 1.4224)
			(drill 1.016)
			(layers "*.Cu" "*.Mask")
			(remove_unused_layers no)
			(net "FAN_TACH6")
			(clearance 0.1524)
			(thermal_gap 0.1524)
		)
		(pad "4" thru_hole circle
			(at 2.54 0 270)
			(size 1.4224 1.4224)
			(drill 1.016)
			(layers "*.Cu" "*.Mask")
			(remove_unused_layers no)
			(net "PWM_OUT_FAN3_NET")
			(clearance 0.1524)
			(thermal_gap 0.1524)
		)
		(pad "5" thru_hole circle
			(at 5.08 0 270)
			(size 1.4224 1.4224)
			(drill 1.016)
			(layers "*.Cu" "*.Mask")
			(remove_unused_layers no)
			(net "FAN_TACH5")
			(clearance 0.1524)
			(thermal_gap 0.1524)
		)
	)
	(footprint ""
		(layer "F.Cu")
		(at 11.9634 -232.7656 90)
		(property "Reference" "R34"
			(at 0 0 90)
			(layer "F.SilkS")
			(hide yes)
			(effects
				(font
					(size 1.27 1.27)
				)
			)
		)
		(property "Value" "0R2J-2-GP"
			(at 0.064008 -3.993896 90)
			(unlocked yes)
			(layer "F.Fab")
			(hide yes)
			(effects
				(font
					(size 1.016 1.016)
					(thickness 0.1524)
				)
			)
		)
		(property "Device Type" "R402H16"
			(at 0.064008 -5.517896 90)
			(unlocked yes)
			(layer "F.Fab")
			(hide yes)
			(effects
				(font
					(size 1.016 1.016)
					(thickness 0.1524)
				)
			)
		)
		(duplicate_pad_numbers_are_jumpers no)
		(fp_line
			(start 0.508 -0.9398)
			(end -0.508 -0.9398)
			(stroke
				(width 0.1524)
				(type default)
			)
			(layer "F.SilkS")
		)
		(fp_line
			(start -0.508 -0.9398)
			(end -0.508 0.9398)
			(stroke
				(width 0.1524)
				(type default)
			)
			(layer "F.SilkS")
		)
		(fp_rect
			(start -0.508 0.9398)
			(end 0.508 -0.9398)
			(stroke
				(width 0)
				(type default)
			)
			(fill no)
			(layer "F.CrtYd")
		)
		(fp_rect
			(start -0.508 0.9398)
			(end 0.508 -0.9398)
			(stroke
				(width 0)
				(type default)
			)
			(fill no)
			(layer "F.Fab")
		)
		(pad "1" smd custom
			(at 0 -0.4445 90)
			(size 0.1397 0.1397)
			(layers "F.Cu" "F.Mask" "F.Paste")
			(net "LED_DR_LED3_K")
			(options
				(clearance outline)
				(anchor circle)
			)
			(primitives
				(gr_poly
					(pts
						(arc
							(start -0.1778 -0.2794)
							(mid -0.249642 -0.249642)
							(end -0.2794 -0.1778)
						)
						(arc
							(start -0.2794 0.1778)
							(mid -0.249642 0.249642)
							(end -0.1778 0.2794)
						)
						(arc
							(start 0.1778 0.2794)
							(mid 0.249642 0.249642)
							(end 0.2794 0.1778)
						)
						(arc
							(start 0.2794 -0.1778)
							(mid 0.249642 -0.249642)
							(end 0.1778 -0.2794)
						)
					)
					(width 0)
					(fill yes)
				)
			)
		)
		(pad "2" smd custom
			(at 0 0.4445 90)
			(size 0.1397 0.1397)
			(layers "F.Cu" "F.Mask" "F.Paste")
			(net "GND")
			(options
				(clearance outline)
				(anchor circle)
			)
			(primitives
				(gr_poly
					(pts
						(arc
							(start -0.1778 -0.2794)
							(mid -0.249642 -0.249642)
							(end -0.2794 -0.1778)
						)
						(arc
							(start -0.2794 0.1778)
							(mid -0.249642 0.249642)
							(end -0.1778 0.2794)
						)
						(arc
							(start 0.1778 0.2794)
							(mid 0.249642 0.249642)
							(end 0.2794 0.1778)
						)
						(arc
							(start 0.2794 -0.1778)
							(mid 0.249642 -0.249642)
							(end 0.1778 -0.2794)
						)
					)
					(width 0)
					(fill yes)
				)
			)
		)
	)
)
